(kicad_pcb
	(version 20260206)
	(generator "pcbnew")
	(generator_version "10.0")
	(general
		(thickness 1.6)
		(legacy_teardrops no)
	)
	(paper "A4")
	(title_block
		(title "timecard-production-celestica-r4006 — R4006-B0001-02_R01.brd")
		(comment 1 "Time Appliance Project (Time Card) / footprint 197 of 1113 (U24), pads 112-224 of 484")
	)
	(layers
		(0 "F.Cu" signal "TOP")
		(4 "In1.Cu" signal "L02_GND1")
		(6 "In2.Cu" signal "L03_SIG1")
		(8 "In3.Cu" signal "L04_GND2")
		(10 "In4.Cu" signal "L05_VCC1")
		(12 "In5.Cu" signal "L06_VCC2")
		(14 "In6.Cu" signal "L07_GND3")
		(16 "In7.Cu" signal "L08_SIG2")
		(18 "In8.Cu" signal "L09_GND4")
		(2 "B.Cu" signal "BOTTOM")
		(9 "F.Adhes" user "F.Adhesive")
		(11 "B.Adhes" user "B.Adhesive")
		(13 "F.Paste" user "Package Geometry/Pastemask Top")
		(15 "B.Paste" user "Package Geometry/Pastemask Bottom")
		(5 "F.SilkS" user "Ref Des/Silkscreen Top")
		(7 "B.SilkS" user "Ref Des/Silkscreen Bottom")
		(1 "F.Mask" user "Board Geometry/Soldermask Top")
		(3 "B.Mask" user "Board Geometry/Soldermask Bottom")
		(17 "Dwgs.User" user "User.Drawings")
		(19 "Cmts.User" user "User.Comments")
		(21 "Eco1.User" user "User.Eco1")
		(23 "Eco2.User" user "User.Eco2")
		(25 "Edge.Cuts" user "Board Geometry/Outline")
		(27 "Margin" user)
		(31 "F.CrtYd" user "Package Geometry/Place Bound Top")
		(29 "B.CrtYd" user "Package Geometry/Place Bound Bottom")
		(35 "F.Fab" user "Ref Des/Assembly Top")
		(33 "B.Fab" user "Ref Des/Assembly Bottom")
	)
	(footprint ""
		(layer "F.Cu")
		(at 109.347 -44.323 90)
		(property "Reference" "U24"
			(at 12.27963 3.683 0)
			(unlocked yes)
			(layer "F.SilkS")
			(effects
				(font
					(size 0.7874 0.5842)
					(thickness 0.1524)
				)
			)
		)
		(property "Value" ""
			(at 0 0 90)
			(layer "F.Fab")
			(effects
				(font
					(size 1.27 1.27)
				)
			)
		)
		(property "User Part Number" "PARTNUM*"
			(at 0 14.056868 90)
			(unlocked yes)
			(layer "Cmts.User")
			(hide yes)
			(effects
				(font
					(size 0.7874 0.5842)
					(thickness 0.1524)
				)
			)
		)
		(property "Device Type" "XC7A200T_2FBG484C_FBG484-G240-A"
			(at 0 12.863068 90)
			(unlocked yes)
			(layer "F.Fab")
			(hide yes)
			(effects
				(font
					(size 0.7874 0.5842)
					(thickness 0.1524)
				)
			)
		)
		(duplicate_pad_numbers_are_jumpers no)
		(pad "D2" smd circle
			(at -9.500108 -7.499858 90)
			(size 0.50038 0.50038)
			(layers "F.Cu" "F.Mask" "F.Paste")
			(net "Net_137")
		)
		(pad "D3" smd circle
			(at -8.50011 -7.499858 90)
			(size 0.50038 0.50038)
			(layers "F.Cu" "F.Mask" "F.Paste")
			(net "SG")
		)
		(pad "D4" smd circle
			(at -7.499858 -7.499858 90)
			(size 0.50038 0.50038)
			(layers "F.Cu" "F.Mask" "F.Paste")
			(net "SG")
		)
		(pad "D5" smd circle
			(at -6.49986 -7.499858 90)
			(size 0.50038 0.50038)
			(layers "F.Cu" "F.Mask" "F.Paste")
			(net "CPU_RX_PCIE_MGT1_TXP")
		)
		(pad "D6" smd circle
			(at -5.499862 -7.499858 90)
			(size 0.50038 0.50038)
			(layers "F.Cu" "F.Mask" "F.Paste")
			(net "XP1R0V_FPGA_MGTAVCC")
		)
		(pad "D7" smd circle
			(at -4.499864 -7.499858 90)
			(size 0.50038 0.50038)
			(layers "F.Cu" "F.Mask" "F.Paste")
			(net "CPU_RX_PCIE_MGT3_TXP")
		)
		(pad "D8" smd circle
			(at -3.499866 -7.499858 90)
			(size 0.50038 0.50038)
			(layers "F.Cu" "F.Mask" "F.Paste")
			(net "SG")
		)
		(pad "D9" smd circle
			(at -2.499868 -7.499858 90)
			(size 0.50038 0.50038)
			(layers "F.Cu" "F.Mask" "F.Paste")
			(net "CPU_TX_PCIE_MGT_3_RXP")
		)
		(pad "D10" smd circle
			(at -1.49987 -7.499858 90)
			(size 0.50038 0.50038)
			(layers "F.Cu" "F.Mask" "F.Paste")
			(net "XP1R0V_FPGA_MGTAVCC")
		)
		(pad "D11" smd circle
			(at -0.499872 -7.499858 90)
			(size 0.50038 0.50038)
			(layers "F.Cu" "F.Mask" "F.Paste")
			(net "CPU_TX_PCIE_MGT_1_RXP")
		)
		(pad "D12" smd circle
			(at 0.500126 -7.499858 90)
			(size 0.50038 0.50038)
			(layers "F.Cu" "F.Mask" "F.Paste")
			(net "SG")
		)
		(pad "D13" smd circle
			(at 1.500124 -7.499858 90)
			(size 0.50038 0.50038)
			(layers "F.Cu" "F.Mask" "F.Paste")
			(net "SG")
		)
		(pad "D14" smd circle
			(at 2.500122 -7.499858 90)
			(size 0.50038 0.50038)
			(layers "F.Cu" "F.Mask" "F.Paste")
			(net "LED_DATOUT2")
		)
		(pad "D15" smd circle
			(at 3.50012 -7.499858 90)
			(size 0.50038 0.50038)
			(layers "F.Cu" "F.Mask" "F.Paste")
			(net "LED_DATOUT3")
		)
		(pad "D16" smd circle
			(at 4.500118 -7.499858 90)
			(size 0.50038 0.50038)
			(layers "F.Cu" "F.Mask" "F.Paste")
			(net "Net_75")
		)
		(pad "D17" smd circle
			(at 5.500116 -7.499858 90)
			(size 0.50038 0.50038)
			(layers "F.Cu" "F.Mask" "F.Paste")
			(net "FPGA_OUT_SMA3_LED_BLUE_N")
		)
		(pad "D18" smd circle
			(at 6.500114 -7.499858 90)
			(size 0.50038 0.50038)
			(layers "F.Cu" "F.Mask" "F.Paste")
			(net "XP3R3V_FPGA")
		)
		(pad "D19" smd circle
			(at 7.500112 -7.499858 90)
			(size 0.50038 0.50038)
			(layers "F.Cu" "F.Mask" "F.Paste")
			(net "FPGA_OUT_SMA4_LED_GREEN_N")
		)
		(pad "D20" smd circle
			(at 8.50011 -7.499858 90)
			(size 0.50038 0.50038)
			(layers "F.Cu" "F.Mask" "F.Paste")
			(net "Net_58")
		)
		(pad "D21" smd circle
			(at 9.500108 -7.499858 90)
			(size 0.50038 0.50038)
			(layers "F.Cu" "F.Mask" "F.Paste")
			(net "IO_L23N_16")
		)
		(pad "D22" smd circle
			(at 10.500106 -7.499858 90)
			(size 0.50038 0.50038)
			(layers "F.Cu" "F.Mask" "F.Paste")
			(net "IO_L22N_16")
		)
		(pad "E1" smd circle
			(at -10.500106 -6.49986 90)
			(size 0.50038 0.50038)
			(layers "F.Cu" "F.Mask" "F.Paste")
			(net "Net_135")
		)
		(pad "E2" smd circle
			(at -9.500108 -6.49986 90)
			(size 0.50038 0.50038)
			(layers "F.Cu" "F.Mask" "F.Paste")
			(net "Net_139")
		)
		(pad "E3" smd circle
			(at -8.50011 -6.49986 90)
			(size 0.50038 0.50038)
			(layers "F.Cu" "F.Mask" "F.Paste")
			(net "Net_147")
		)
		(pad "E4" smd circle
			(at -7.499858 -6.49986 90)
			(size 0.50038 0.50038)
			(layers "F.Cu" "F.Mask" "F.Paste")
			(net "SG")
		)
		(pad "E5" smd circle
			(at -6.49986 -6.49986 90)
			(size 0.50038 0.50038)
			(layers "F.Cu" "F.Mask" "F.Paste")
			(net "SG")
		)
		(pad "E6" smd circle
			(at -5.499862 -6.49986 90)
			(size 0.50038 0.50038)
			(layers "F.Cu" "F.Mask" "F.Paste")
			(net "MHZ125CLKN_CLKIN")
		)
		(pad "E7" smd circle
			(at -4.499864 -6.49986 90)
			(size 0.50038 0.50038)
			(layers "F.Cu" "F.Mask" "F.Paste")
			(net "SG")
		)
		(pad "E8" smd circle
			(at -3.499866 -6.49986 90)
			(size 0.50038 0.50038)
			(layers "F.Cu" "F.Mask" "F.Paste")
			(net "XP1R0V_FPGA_MGTAVCC")
		)
		(pad "E9" smd circle
			(at -2.499868 -6.49986 90)
			(size 0.50038 0.50038)
			(layers "F.Cu" "F.Mask" "F.Paste")
			(net "SG")
		)
		(pad "E10" smd circle
			(at -1.49987 -6.49986 90)
			(size 0.50038 0.50038)
			(layers "F.Cu" "F.Mask" "F.Paste")
			(net "PCIE_REFCLKN")
		)
		(pad "E11" smd circle
			(at -0.499872 -6.49986 90)
			(size 0.50038 0.50038)
			(layers "F.Cu" "F.Mask" "F.Paste")
			(net "SG")
		)
		(pad "E12" smd circle
			(at 0.500126 -6.49986 90)
			(size 0.50038 0.50038)
			(layers "F.Cu" "F.Mask" "F.Paste")
			(net "XP1R8V_FPGA_VCCAUX")
		)
		(pad "E13" smd circle
			(at 1.500124 -6.49986 90)
			(size 0.50038 0.50038)
			(layers "F.Cu" "F.Mask" "F.Paste")
			(net "FPGA_OUT_SMA2_LED_RED_N")
		)
		(pad "E14" smd circle
			(at 2.500122 -6.49986 90)
			(size 0.50038 0.50038)
			(layers "F.Cu" "F.Mask" "F.Paste")
			(net "Net_86")
		)
		(pad "E15" smd circle
			(at 3.50012 -6.49986 90)
			(size 0.50038 0.50038)
			(layers "F.Cu" "F.Mask" "F.Paste")
			(net "XP3R3V_FPGA")
		)
		(pad "E16" smd circle
			(at 4.500118 -6.49986 90)
			(size 0.50038 0.50038)
			(layers "F.Cu" "F.Mask" "F.Paste")
			(net "Net_76")
		)
		(pad "E17" smd circle
			(at 5.500116 -6.49986 90)
			(size 0.50038 0.50038)
			(layers "F.Cu" "F.Mask" "F.Paste")
			(net "Net_69")
		)
		(pad "E18" smd circle
			(at 6.500114 -6.49986 90)
			(size 0.50038 0.50038)
			(layers "F.Cu" "F.Mask" "F.Paste")
			(net "Net_40")
		)
		(pad "E19" smd circle
			(at 7.500112 -6.49986 90)
			(size 0.50038 0.50038)
			(layers "F.Cu" "F.Mask" "F.Paste")
			(net "FPGA_OUT_SMA4_LED_BLUE_N")
		)
		(pad "E20" smd circle
			(at 8.50011 -6.49986 90)
			(size 0.50038 0.50038)
			(layers "F.Cu" "F.Mask" "F.Paste")
			(net "SG")
		)
		(pad "E21" smd circle
			(at 9.500108 -6.49986 90)
			(size 0.50038 0.50038)
			(layers "F.Cu" "F.Mask" "F.Paste")
			(net "IO_L23P_16")
		)
		(pad "E22" smd circle
			(at 10.500106 -6.49986 90)
			(size 0.50038 0.50038)
			(layers "F.Cu" "F.Mask" "F.Paste")
			(net "IO_L22P_16")
		)
		(pad "F1" smd circle
			(at -10.500106 -5.499862 90)
			(size 0.50038 0.50038)
			(layers "F.Cu" "F.Mask" "F.Paste")
			(net "Net_142")
		)
		(pad "F2" smd circle
			(at -9.500108 -5.499862 90)
			(size 0.50038 0.50038)
			(layers "F.Cu" "F.Mask" "F.Paste")
			(net "XP2R5V_FPGA")
		)
		(pad "F3" smd circle
			(at -8.50011 -5.499862 90)
			(size 0.50038 0.50038)
			(layers "F.Cu" "F.Mask" "F.Paste")
			(net "Net_149")
		)
		(pad "F4" smd circle
			(at -7.499858 -5.499862 90)
			(size 0.50038 0.50038)
			(layers "F.Cu" "F.Mask" "F.Paste")
			(net "Net_87")
		)
		(pad "F5" smd circle
			(at -6.49986 -5.499862 90)
			(size 0.50038 0.50038)
			(layers "F.Cu" "F.Mask" "F.Paste")
			(net "SG")
		)
		(pad "F6" smd circle
			(at -5.499862 -5.499862 90)
			(size 0.50038 0.50038)
			(layers "F.Cu" "F.Mask" "F.Paste")
			(net "MHZ125CLKP_CLKIN")
		)
		(pad "F7" smd circle
			(at -4.499864 -5.499862 90)
			(size 0.50038 0.50038)
			(layers "F.Cu" "F.Mask" "F.Paste")
			(net "XP1R0V_FPGA_MGTAVCC")
		)
		(pad "F8" smd circle
			(at -3.499866 -5.499862 90)
			(size 0.50038 0.50038)
			(layers "F.Cu" "F.Mask" "F.Paste")
			(net "FPGA_MGTRREF")
		)
		(pad "F9" smd circle
			(at -2.499868 -5.499862 90)
			(size 0.50038 0.50038)
			(layers "F.Cu" "F.Mask" "F.Paste")
			(net "XP1R0V_FPGA_MGTAVCC")
		)
		(pad "F10" smd circle
			(at -1.49987 -5.499862 90)
			(size 0.50038 0.50038)
			(layers "F.Cu" "F.Mask" "F.Paste")
			(net "PCIE_REFCLKP")
		)
		(pad "F11" smd circle
			(at -0.499872 -5.499862 90)
			(size 0.50038 0.50038)
			(layers "F.Cu" "F.Mask" "F.Paste")
			(net "SG")
		)
		(pad "F12" smd circle
			(at 0.500126 -5.499862 90)
			(size 0.50038 0.50038)
			(layers "F.Cu" "F.Mask" "F.Paste")
			(net "XP3R3V_FPGA")
		)
		(pad "F13" smd circle
			(at 1.500124 -5.499862 90)
			(size 0.50038 0.50038)
			(layers "F.Cu" "F.Mask" "F.Paste")
			(net "FPGA_OUT_SMA1_LED_BLUE_N")
		)
		(pad "F14" smd circle
			(at 2.500122 -5.499862 90)
			(size 0.50038 0.50038)
			(layers "F.Cu" "F.Mask" "F.Paste")
			(net "FPGA_OUT_SMA1_LED_GREEN_N")
		)
		(pad "F15" smd circle
			(at 3.50012 -5.499862 90)
			(size 0.50038 0.50038)
			(layers "F.Cu" "F.Mask" "F.Paste")
			(net "Net_28")
		)
		(pad "F16" smd circle
			(at 4.500118 -5.499862 90)
			(size 0.50038 0.50038)
			(layers "F.Cu" "F.Mask" "F.Paste")
			(net "FPGA_OUT_SMA1_LED_RED_N")
		)
		(pad "F17" smd circle
			(at 5.500116 -5.499862 90)
			(size 0.50038 0.50038)
			(layers "F.Cu" "F.Mask" "F.Paste")
			(net "SG")
		)
		(pad "F18" smd circle
			(at 6.500114 -5.499862 90)
			(size 0.50038 0.50038)
			(layers "F.Cu" "F.Mask" "F.Paste")
			(net "FPGA_OUT_SMA4_LED_RED_N")
		)
		(pad "F19" smd circle
			(at 7.500112 -5.499862 90)
			(size 0.50038 0.50038)
			(layers "F.Cu" "F.Mask" "F.Paste")
			(net "Net_54")
		)
		(pad "F20" smd circle
			(at 8.50011 -5.499862 90)
			(size 0.50038 0.50038)
			(layers "F.Cu" "F.Mask" "F.Paste")
			(net "Net_51")
		)
		(pad "F21" smd circle
			(at 9.500108 -5.499862 90)
			(size 0.50038 0.50038)
			(layers "F.Cu" "F.Mask" "F.Paste")
			(net "Net_30")
		)
		(pad "F22" smd circle
			(at 10.500106 -5.499862 90)
			(size 0.50038 0.50038)
			(layers "F.Cu" "F.Mask" "F.Paste")
			(net "XP3R3V_FPGA")
		)
		(pad "G1" smd circle
			(at -10.500106 -4.499864 90)
			(size 0.50038 0.50038)
			(layers "F.Cu" "F.Mask" "F.Paste")
			(net "Net_145")
		)
		(pad "G2" smd circle
			(at -9.500108 -4.499864 90)
			(size 0.50038 0.50038)
			(layers "F.Cu" "F.Mask" "F.Paste")
			(net "Net_156")
		)
		(pad "G3" smd circle
			(at -8.50011 -4.499864 90)
			(size 0.50038 0.50038)
			(layers "F.Cu" "F.Mask" "F.Paste")
			(net "Net_95")
		)
		(pad "G4" smd circle
			(at -7.499858 -4.499864 90)
			(size 0.50038 0.50038)
			(layers "F.Cu" "F.Mask" "F.Paste")
			(net "Net_99")
		)
		(pad "G5" smd circle
			(at -6.49986 -4.499864 90)
			(size 0.50038 0.50038)
			(layers "F.Cu" "F.Mask" "F.Paste")
			(net "SG")
		)
		(pad "G6" smd circle
			(at -5.499862 -4.499864 90)
			(size 0.50038 0.50038)
			(layers "F.Cu" "F.Mask" "F.Paste")
			(net "SG")
		)
		(pad "G7" smd circle
			(at -4.499864 -4.499864 90)
			(size 0.50038 0.50038)
			(layers "F.Cu" "F.Mask" "F.Paste")
			(net "SG")
		)
		(pad "G8" smd circle
			(at -3.499866 -4.499864 90)
			(size 0.50038 0.50038)
			(layers "F.Cu" "F.Mask" "F.Paste")
			(net "SG")
		)
		(pad "G9" smd circle
			(at -2.499868 -4.499864 90)
			(size 0.50038 0.50038)
			(layers "F.Cu" "F.Mask" "F.Paste")
			(net "SG")
		)
		(pad "G10" smd circle
			(at -1.49987 -4.499864 90)
			(size 0.50038 0.50038)
			(layers "F.Cu" "F.Mask" "F.Paste")
			(net "SG")
		)
		(pad "G11" smd circle
			(at -0.499872 -4.499864 90)
			(size 0.50038 0.50038)
			(layers "F.Cu" "F.Mask" "F.Paste")
			(net "FPGA_DONE")
		)
		(pad "G12" smd circle
			(at 0.500126 -4.499864 90)
			(size 0.50038 0.50038)
			(layers "F.Cu" "F.Mask" "F.Paste")
			(net "SG")
		)
		(pad "G13" smd circle
			(at 1.500124 -4.499864 90)
			(size 0.50038 0.50038)
			(layers "F.Cu" "F.Mask" "F.Paste")
			(net "FPGA_OUT_MUX2_SEL")
		)
		(pad "G14" smd circle
			(at 2.500122 -4.499864 90)
			(size 0.50038 0.50038)
			(layers "F.Cu" "F.Mask" "F.Paste")
			(net "SG")
		)
		(pad "G15" smd circle
			(at 3.50012 -4.499864 90)
			(size 0.50038 0.50038)
			(layers "F.Cu" "F.Mask" "F.Paste")
			(net "FPGA_OUT_MUX3_SEL")
		)
		(pad "G16" smd circle
			(at 4.500118 -4.499864 90)
			(size 0.50038 0.50038)
			(layers "F.Cu" "F.Mask" "F.Paste")
			(net "Net_68")
		)
		(pad "G17" smd circle
			(at 5.500116 -4.499864 90)
			(size 0.50038 0.50038)
			(layers "F.Cu" "F.Mask" "F.Paste")
			(net "Net_173")
		)
		(pad "G18" smd circle
			(at 6.500114 -4.499864 90)
			(size 0.50038 0.50038)
			(layers "F.Cu" "F.Mask" "F.Paste")
			(net "Net_73")
		)
		(pad "G19" smd circle
			(at 7.500112 -4.499864 90)
			(size 0.50038 0.50038)
			(layers "F.Cu" "F.Mask" "F.Paste")
			(net "XP3R3V_FPGA")
		)
		(pad "G20" smd circle
			(at 8.50011 -4.499864 90)
			(size 0.50038 0.50038)
			(layers "F.Cu" "F.Mask" "F.Paste")
			(net "FPGA_IO_3")
		)
		(pad "G21" smd circle
			(at 9.500108 -4.499864 90)
			(size 0.50038 0.50038)
			(layers "F.Cu" "F.Mask" "F.Paste")
			(net "IO_L24P_16")
		)
		(pad "G22" smd circle
			(at 10.500106 -4.499864 90)
			(size 0.50038 0.50038)
			(layers "F.Cu" "F.Mask" "F.Paste")
			(net "IO_L24N_16")
		)
		(pad "H1" smd circle
			(at -10.500106 -3.499866 90)
			(size 0.50038 0.50038)
			(layers "F.Cu" "F.Mask" "F.Paste")
			(net "SG")
		)
		(pad "H2" smd circle
			(at -9.500108 -3.499866 90)
			(size 0.50038 0.50038)
			(layers "F.Cu" "F.Mask" "F.Paste")
			(net "Net_157")
		)
		(pad "H3" smd circle
			(at -8.50011 -3.499866 90)
			(size 0.50038 0.50038)
			(layers "F.Cu" "F.Mask" "F.Paste")
			(net "Net_97")
		)
		(pad "H4" smd circle
			(at -7.499858 -3.499866 90)
			(size 0.50038 0.50038)
			(layers "F.Cu" "F.Mask" "F.Paste")
			(net "Net_101")
		)
		(pad "H5" smd circle
			(at -6.49986 -3.499866 90)
			(size 0.50038 0.50038)
			(layers "F.Cu" "F.Mask" "F.Paste")
			(net "Net_91")
		)
		(pad "H6" smd circle
			(at -5.499862 -3.499866 90)
			(size 0.50038 0.50038)
			(layers "F.Cu" "F.Mask" "F.Paste")
			(net "XP2R5V_FPGA")
		)
		(pad "H7" smd circle
			(at -4.499864 -3.499866 90)
			(size 0.50038 0.50038)
			(layers "F.Cu" "F.Mask" "F.Paste")
			(net "SG")
		)
		(pad "H8" smd circle
			(at -3.499866 -3.499866 90)
			(size 0.50038 0.50038)
			(layers "F.Cu" "F.Mask" "F.Paste")
			(net "XP1R0V_FPGA_VCCINT")
		)
		(pad "H9" smd circle
			(at -2.499868 -3.499866 90)
			(size 0.50038 0.50038)
			(layers "F.Cu" "F.Mask" "F.Paste")
			(net "SG")
		)
		(pad "H10" smd circle
			(at -1.49987 -3.499866 90)
			(size 0.50038 0.50038)
			(layers "F.Cu" "F.Mask" "F.Paste")
			(net "XP1R0V_FPGA_VCCINT")
		)
		(pad "H11" smd circle
			(at -0.499872 -3.499866 90)
			(size 0.50038 0.50038)
			(layers "F.Cu" "F.Mask" "F.Paste")
			(net "SG")
		)
		(pad "H12" smd circle
			(at 0.500126 -3.499866 90)
			(size 0.50038 0.50038)
			(layers "F.Cu" "F.Mask" "F.Paste")
			(net "XP1R8V_FPGA_VCCAUX")
		)
		(pad "H13" smd circle
			(at 1.500124 -3.499866 90)
			(size 0.50038 0.50038)
			(layers "F.Cu" "F.Mask" "F.Paste")
			(net "FPGA_OUT_MUX1_SEL")
		)
		(pad "H14" smd circle
			(at 2.500122 -3.499866 90)
			(size 0.50038 0.50038)
			(layers "F.Cu" "F.Mask" "F.Paste")
			(net "SMA4_SIG_OUT_BF_EN_N")
		)
		(pad "H15" smd circle
			(at 3.50012 -3.499866 90)
			(size 0.50038 0.50038)
			(layers "F.Cu" "F.Mask" "F.Paste")
			(net "SMA3_SIG_IN_BF_EN_N")
		)
		(pad "H16" smd circle
			(at 4.500118 -3.499866 90)
			(size 0.50038 0.50038)
			(layers "F.Cu" "F.Mask" "F.Paste")
			(net "XP3R3V_FPGA")
		)
		(pad "H17" smd circle
			(at 5.500116 -3.499866 90)
			(size 0.50038 0.50038)
			(layers "F.Cu" "F.Mask" "F.Paste")
			(net "Net_174")
		)
		(pad "H18" smd circle
			(at 6.500114 -3.499866 90)
			(size 0.50038 0.50038)
			(layers "F.Cu" "F.Mask" "F.Paste")
			(net "Net_78")
		)
		(pad "H19" smd circle
			(at 7.500112 -3.499866 90)
			(size 0.50038 0.50038)
			(layers "F.Cu" "F.Mask" "F.Paste")
			(net "FPGA_OUT_SHT3X_RST_N")
		)
		(pad "H20" smd circle
			(at 8.50011 -3.499866 90)
			(size 0.50038 0.50038)
			(layers "F.Cu" "F.Mask" "F.Paste")
			(net "FPGA_IO_2")
		)
		(pad "H21" smd circle
			(at 9.500108 -3.499866 90)
			(size 0.50038 0.50038)
			(layers "F.Cu" "F.Mask" "F.Paste")
			(net "SG")
		)
		(pad "H22" smd circle
			(at 10.500106 -3.499866 90)
			(size 0.50038 0.50038)
			(layers "F.Cu" "F.Mask" "F.Paste")
			(net "FPGA_IO_1")
		)
		(pad "J1" smd circle
			(at -10.500106 -2.499868 90)
			(size 0.50038 0.50038)
			(layers "F.Cu" "F.Mask" "F.Paste")
			(net "Net_152")
		)
		(pad "J2" smd circle
			(at -9.500108 -2.499868 90)
			(size 0.50038 0.50038)
			(layers "F.Cu" "F.Mask" "F.Paste")
			(net "Net_159")
		)
		(pad "J3" smd circle
			(at -8.50011 -2.499868 90)
			(size 0.50038 0.50038)
			(layers "F.Cu" "F.Mask" "F.Paste")
			(net "XP2R5V_FPGA")
		)
		(pad "J4" smd circle
			(at -7.499858 -2.499868 90)
			(size 0.50038 0.50038)
			(layers "F.Cu" "F.Mask" "F.Paste")
			(net "Net_102")
		)
	)
)
